# S9S_MB_2U (Grand Teton) — schematic netlist excerpt (pin names and nets, part order shuffled) for the footprints in the layout excerpt that follows; sources: Cadence DE-HDL packaged netlist, KiCad conversion of 03242023_DA0F0TMBIJ0_F0T_Motherboard_J_brd_V01_OCP.brd

C1548  Q_CAP_DIFFBUS  DIFF BUS_0.22UF 6.3V 20% X6S  pkg C0201  page 175 : \1\ = P5E_CPU0_PE4_TX_C_DN<15> ; \2\ = P5E_CPU0_PE4_TX_DN<15>
C2449  Q_CAP  100NF 50V 10% X7R  pkg C0402  page 284 : A = PVNN_TERM_CPU1 ; B = GND
PC237  Q_CAP  680PF 50V 10% X7R  pkg 0402  page 282 : A = PVNN_MAIN_CPU0_FB ; B = PVNN_MAIN_CPU0_FB_RC

(kicad_pcb
	(version 20260206)
	(generator "pcbnew")
	(generator_version "10.0")
	(general
		(thickness 1.6)
		(legacy_teardrops no)
	)
	(paper "A4")
	(title_block
		(title "03242023_DA0F0TMBIJ0_F0T_Motherboard_J_brd_V01_OCP.brd")
		(comment 1 "Grand Teton / footprints 3965-3967 of 6105")
	)
	(layers
		(0 "F.Cu" signal "TOP")
		(4 "In1.Cu" signal "GND")
		(6 "In2.Cu" signal "IN1")
		(8 "In3.Cu" signal "GND1")
		(10 "In4.Cu" signal "IN2")
		(12 "In5.Cu" signal "GND2")
		(14 "In6.Cu" signal "IN3")
		(16 "In7.Cu" signal "GND3")
		(18 "In8.Cu" signal "VCC")
		(20 "In9.Cu" signal "VCC1")
		(22 "In10.Cu" signal "GND4")
		(24 "In11.Cu" signal "IN4")
		(26 "In12.Cu" signal "GND5")
		(28 "In13.Cu" signal "IN5")
		(30 "In14.Cu" signal "GND6")
		(32 "In15.Cu" signal "IN6")
		(34 "In16.Cu" signal "GND7")
		(2 "B.Cu" signal "BOTTOM")
		(9 "F.Adhes" user "F.Adhesive")
		(11 "B.Adhes" user "B.Adhesive")
		(13 "F.Paste" user "Package Geometry/Pastemask Top")
		(15 "B.Paste" user "Package Geometry/Pastemask Bottom")
		(5 "F.SilkS" user "Ref Des/Silkscreen Top")
		(7 "B.SilkS" user "Ref Des/Silkscreen Bottom")
		(1 "F.Mask" user "Board Geometry/Soldermask Top")
		(3 "B.Mask" user "Board Geometry/Soldermask Bottom")
		(17 "Dwgs.User" user "User.Drawings")
		(19 "Cmts.User" user "User.Comments")
		(21 "Eco1.User" user "User.Eco1")
		(23 "Eco2.User" user "User.Eco2")
		(25 "Edge.Cuts" user "Board Geometry/Outline")
		(27 "Margin" user)
		(31 "F.CrtYd" user "Package Geometry/Place Bound Top")
		(29 "B.CrtYd" user "Package Geometry/Place Bound Bottom")
		(35 "F.Fab" user "Ref Des/Assembly Top")
		(33 "B.Fab" user "Ref Des/Assembly Bottom")
	)
	(footprint ""
		(layer "F.Cu")
		(at 349.903288 -402.371052 -90)
		(property "Reference" "C1548"
			(at 0 0 270)
			(layer "F.SilkS")
			(hide yes)
			(effects
				(font
					(size 1.27 1.27)
				)
			)
		)
		(property "Value" ""
			(at 0 0 270)
			(layer "F.Fab")
			(effects
				(font
					(size 1.27 1.27)
				)
			)
		)
		(duplicate_pad_numbers_are_jumpers no)
		(fp_line
			(start -0.299974 0.150114)
			(end -0.299974 -0.150114)
			(stroke
				(width 0.1)
				(type default)
			)
			(layer "F.Fab")
		)
		(fp_line
			(start 0.299974 0.150114)
			(end -0.299974 0.150114)
			(stroke
				(width 0.1)
				(type default)
			)
			(layer "F.Fab")
		)
		(fp_line
			(start -0.299974 -0.150114)
			(end 0.299974 -0.150114)
			(stroke
				(width 0.1)
				(type default)
			)
			(layer "F.Fab")
		)
		(fp_line
			(start 0.299974 -0.150114)
			(end 0.299974 0.150114)
			(stroke
				(width 0.1)
				(type default)
			)
			(layer "F.Fab")
		)
		(pad "1" smd rect
			(at -0.2667 0 270)
			(size 0.3048 0.381)
			(layers "F.Cu" "F.Mask" "F.Paste")
			(net "P5E_CPU0_PE4_TX_C_DN<15>")
		)
		(pad "2" smd rect
			(at 0.2667 0 270)
			(size 0.3048 0.381)
			(layers "F.Cu" "F.Mask" "F.Paste")
			(net "P5E_CPU0_PE4_TX_DN<15>")
		)
	)
	(footprint ""
		(layer "F.Cu")
		(at 99.999546 -356.625652 -90)
		(property "Reference" "C2449"
			(at 0 0 270)
			(layer "F.SilkS")
			(hide yes)
			(effects
				(font
					(size 1.27 1.27)
				)
			)
		)
		(property "Value" ""
			(at 0 0 270)
			(layer "F.Fab")
			(effects
				(font
					(size 1.27 1.27)
				)
			)
		)
		(duplicate_pad_numbers_are_jumpers no)
		(fp_line
			(start -0.7874 0.4064)
			(end -0.7874 -0.4064)
			(stroke
				(width 0.1524)
				(type default)
			)
			(layer "F.SilkS")
		)
		(fp_line
			(start 0.7874 0.4064)
			(end -0.7874 0.4064)
			(stroke
				(width 0.1524)
				(type default)
			)
			(layer "F.SilkS")
		)
		(fp_line
			(start -0.7874 -0.4064)
			(end 0.7874 -0.4064)
			(stroke
				(width 0.1524)
				(type default)
			)
			(layer "F.SilkS")
		)
		(fp_line
			(start 0.7874 -0.4064)
			(end 0.7874 0.4064)
			(stroke
				(width 0.1524)
				(type default)
			)
			(layer "F.SilkS")
		)
		(fp_line
			(start -0.67945 0.3048)
			(end -0.67945 -0.305054)
			(stroke
				(width 0.1)
				(type default)
			)
			(layer "F.Fab")
		)
		(fp_line
			(start -0.12065 0.3048)
			(end -0.67945 0.3048)
			(stroke
				(width 0.1)
				(type default)
			)
			(layer "F.Fab")
		)
		(fp_line
			(start 0.120396 0.3048)
			(end 0.120396 0.2794)
			(stroke
				(width 0.1)
				(type default)
			)
			(layer "F.Fab")
		)
		(fp_line
			(start 0.67945 0.3048)
			(end 0.120396 0.3048)
			(stroke
				(width 0.1)
				(type default)
			)
			(layer "F.Fab")
		)
		(fp_line
			(start -0.12065 0.2794)
			(end -0.12065 0.3048)
			(stroke
				(width 0.1)
				(type default)
			)
			(layer "F.Fab")
		)
		(fp_line
			(start 0.120396 0.2794)
			(end -0.12065 0.2794)
			(stroke
				(width 0.1)
				(type default)
			)
			(layer "F.Fab")
		)
		(fp_line
			(start -0.12065 -0.2794)
			(end 0.12065 -0.2794)
			(stroke
				(width 0.1)
				(type default)
			)
			(layer "F.Fab")
		)
		(fp_line
			(start 0.12065 -0.2794)
			(end 0.12065 -0.3048)
			(stroke
				(width 0.1)
				(type default)
			)
			(layer "F.Fab")
		)
		(fp_line
			(start 0.12065 -0.3048)
			(end 0.67945 -0.3048)
			(stroke
				(width 0.1)
				(type default)
			)
			(layer "F.Fab")
		)
		(fp_line
			(start 0.67945 -0.3048)
			(end 0.67945 0.3048)
			(stroke
				(width 0.1)
				(type default)
			)
			(layer "F.Fab")
		)
		(fp_line
			(start -0.67945 -0.305054)
			(end -0.12065 -0.305054)
			(stroke
				(width 0.1)
				(type default)
			)
			(layer "F.Fab")
		)
		(fp_line
			(start -0.12065 -0.305054)
			(end -0.12065 -0.2794)
			(stroke
				(width 0.1)
				(type default)
			)
			(layer "F.Fab")
		)
		(pad "1" smd circle
			(at -0.40005 0 270)
			(size 0 0)
			(layers "F.Cu" "F.Mask" "F.Paste")
			(net "PVNN_TERM_CPU1")
		)
		(pad "2" smd circle
			(at 0.40005 0 270)
			(size 0 0)
			(layers "F.Cu" "F.Mask" "F.Paste")
			(net "GND")
		)
	)
	(footprint ""
		(layer "F.Cu")
		(at 432.41468 -174.78502)
		(property "Reference" "PC237"
			(at 0 0 0)
			(layer "F.SilkS")
			(hide yes)
			(effects
				(font
					(size 1.27 1.27)
				)
			)
		)
		(property "Value" ""
			(at 0 0 0)
			(layer "F.Fab")
			(effects
				(font
					(size 1.27 1.27)
				)
			)
		)
		(duplicate_pad_numbers_are_jumpers no)
		(fp_line
			(start -0.7874 -0.4064)
			(end 0.7874 -0.4064)
			(stroke
				(width 0.1524)
				(type default)
			)
			(layer "F.SilkS")
		)
		(fp_line
			(start -0.7874 0.4064)
			(end -0.7874 -0.4064)
			(stroke
				(width 0.1524)
				(type default)
			)
			(layer "F.SilkS")
		)
		(fp_line
			(start 0.7874 -0.4064)
			(end 0.7874 0.4064)
			(stroke
				(width 0.1524)
				(type default)
			)
			(layer "F.SilkS")
		)
		(fp_line
			(start 0.7874 0.4064)
			(end -0.7874 0.4064)
			(stroke
				(width 0.1524)
				(type default)
			)
			(layer "F.SilkS")
		)
		(fp_line
			(start -0.67945 -0.305054)
			(end -0.12065 -0.305054)
			(stroke
				(width 0.1)
				(type default)
			)
			(layer "F.Fab")
		)
		(fp_line
			(start -0.67945 0.3048)
			(end -0.67945 -0.305054)
			(stroke
				(width 0.1)
				(type default)
			)
			(layer "F.Fab")
		)
		(fp_line
			(start -0.12065 -0.305054)
			(end -0.12065 -0.2794)
			(stroke
				(width 0.1)
				(type default)
			)
			(layer "F.Fab")
		)
		(fp_line
			(start -0.12065 -0.2794)
			(end 0.12065 -0.2794)
			(stroke
				(width 0.1)
				(type default)
			)
			(layer "F.Fab")
		)
		(fp_line
			(start -0.12065 0.2794)
			(end -0.12065 0.3048)
			(stroke
				(width 0.1)
				(type default)
			)
			(layer "F.Fab")
		)
		(fp_line
			(start -0.12065 0.3048)
			(end -0.67945 0.3048)
			(stroke
				(width 0.1)
				(type default)
			)
			(layer "F.Fab")
		)
		(fp_line
			(start 0.120396 0.2794)
			(end -0.12065 0.2794)
			(stroke
				(width 0.1)
				(type default)
			)
			(layer "F.Fab")
		)
		(fp_line
			(start 0.120396 0.3048)
			(end 0.120396 0.2794)
			(stroke
				(width 0.1)
				(type default)
			)
			(layer "F.Fab")
		)
		(fp_line
			(start 0.12065 -0.3048)
			(end 0.67945 -0.3048)
			(stroke
				(width 0.1)
				(type default)
			)
			(layer "F.Fab")
		)
		(fp_line
			(start 0.12065 -0.2794)
			(end 0.12065 -0.3048)
			(stroke
				(width 0.1)
				(type default)
			)
			(layer "F.Fab")
		)
		(fp_line
			(start 0.67945 -0.3048)
			(end 0.67945 0.3048)
			(stroke
				(width 0.1)
				(type default)
			)
			(layer "F.Fab")
		)
		(fp_line
			(start 0.67945 0.3048)
			(end 0.120396 0.3048)
			(stroke
				(width 0.1)
				(type default)
			)
			(layer "F.Fab")
		)
		(pad "1" smd circle
			(at -0.40005 0)
			(size 0 0)
			(layers "F.Cu" "F.Mask" "F.Paste")
			(net "PVNN_MAIN_CPU0_FB")
		)
		(pad "2" smd circle
			(at 0.40005 0)
			(size 0 0)
			(layers "F.Cu" "F.Mask" "F.Paste")
			(net "PVNN_MAIN_CPU0_FB_RC")
		)
	)
)
